(kicad_pcb
	(version 20240108)
	(generator "pcbnew")
	(generator_version "8.0")
	(general
		(thickness 1.62)
		(legacy_teardrops no)
	)
	(paper "A4")
	(title_block
		(title "Jetson Orin Baseboard")
		(date "2025-03-12")
		(rev "1.3.4")
		(company "Antmicro Ltd")
		(comment 1 "www.antmicro.com")
		(comment 9 "footprints 590-594 of 677")
	)
	(layers
		(0 "F.Cu" signal)
		(1 "In1.Cu" signal)
		(2 "In2.Cu" signal)
		(3 "In3.Cu" signal)
		(4 "In4.Cu" jumper)
		(5 "In5.Cu" signal)
		(6 "In6.Cu" signal)
		(31 "B.Cu" signal)
		(32 "B.Adhes" user "B.Adhesive")
		(33 "F.Adhes" user "F.Adhesive")
		(34 "B.Paste" user)
		(35 "F.Paste" user)
		(36 "B.SilkS" user "B.Silkscreen")
		(37 "F.SilkS" user "F.Silkscreen")
		(38 "B.Mask" user)
		(39 "F.Mask" user)
		(40 "Dwgs.User" user "User.Drawings")
		(41 "Cmts.User" user "User.Comments")
		(42 "Eco1.User" user "User.Eco1")
		(43 "Eco2.User" user "User.Eco2")
		(44 "Edge.Cuts" user)
		(45 "Margin" user)
		(46 "B.CrtYd" user "B.Courtyard")
		(47 "F.CrtYd" user "F.Courtyard")
		(48 "B.Fab" user)
		(49 "F.Fab" user)
	)
	(footprint "antmicro-footprints:SC-74-6_1.5x2.9mm_P0.95mm"
		(layer "B.Cu")
		(at 109 92.02 180)
		(tags "sc74 sc-74 sot23-6 sot457 tsop6 tsop-6")
		(property "Reference" "U2"
			(at -2.1 -2.33 0)
			(layer "B.SilkS")
			(effects
				(font
					(size 0.7 0.7)
					(thickness 0.15)
				)
				(justify left bottom mirror)
			)
		)
		(property "Value" "74LVC2G07_SOT457"
			(at -2 -2.999 0)
			(layer "B.Fab")
			(effects
				(font
					(size 0.7 0.7)
					(thickness 0.15)
				)
				(justify left bottom mirror)
			)
		)
		(property "Footprint" "antmicro-footprints:SC-74-6_1.5x2.9mm_P0.95mm"
			(at 0 0 180)
			(layer "F.Fab")
			(hide yes)
			(effects
				(font
					(size 1.27 1.27)
					(thickness 0.15)
				)
			)
		)
		(property "Datasheet" "https://www.tme.eu/Document/2ad9356043a4952b9021ef50162f8c34/74LVC2G07.pdf"
			(at 0 0 180)
			(layer "F.Fab")
			(hide yes)
			(effects
				(font
					(size 1.27 1.27)
					(thickness 0.15)
				)
			)
		)
		(property "Author" "Antmicro"
			(at 218 184.04 0)
			(layer "B.Fab")
			(hide yes)
			(effects
				(font
					(size 1 1)
					(thickness 0.15)
				)
				(justify mirror)
			)
		)
		(property "License" "Apache-2.0"
			(at 218 184.04 0)
			(layer "B.Fab")
			(hide yes)
			(effects
				(font
					(size 1 1)
					(thickness 0.15)
				)
				(justify mirror)
			)
		)
		(property "MPN" "74LVC2G07GV,125"
			(at 218 184.04 0)
			(layer "B.Fab")
			(hide yes)
			(effects
				(font
					(size 1 1)
					(thickness 0.15)
				)
				(justify mirror)
			)
		)
		(property "Manufacturer" "Nexperia"
			(at 218 184.04 0)
			(layer "B.Fab")
			(hide yes)
			(effects
				(font
					(size 1 1)
					(thickness 0.15)
				)
				(justify mirror)
			)
		)
		(property ki_fp_filters "SG-74 SOT23-6 TSOP6 SOT457")
		(sheetname "M.2")
		(sheetfile "m-2.kicad_sch")
		(attr smd exclude_from_pos_files exclude_from_bom dnp)
		(fp_circle
			(center -1.11 1.454)
			(end -1.06 1.454)
			(stroke
				(width 0.15)
				(type solid)
			)
			(fill solid)
			(layer "B.SilkS")
		)
		(fp_rect
			(start -1.7 1.7)
			(end 1.7 -1.7)
			(stroke
				(width 0.05)
				(type solid)
			)
			(fill none)
			(layer "B.CrtYd")
		)
		(fp_line
			(start 1.22 1.422)
			(end 1.22 -1.372)
			(stroke
				(width 0.15)
				(type solid)
			)
			(layer "B.Fab")
		)
		(fp_line
			(start 1.22 -1.372)
			(end -1.167 -1.372)
			(stroke
				(width 0.15)
				(type solid)
			)
			(layer "B.Fab")
		)
		(fp_line
			(start -0.76 1.422)
			(end 1.22 1.422)
			(stroke
				(width 0.15)
				(type solid)
			)
			(layer "B.Fab")
		)
		(fp_line
			(start -1.167 -1.372)
			(end -1.269 -1.372)
			(stroke
				(width 0.15)
				(type solid)
			)
			(layer "B.Fab")
		)
		(fp_line
			(start -1.269 0.915)
			(end -0.76 1.422)
			(stroke
				(width 0.15)
				(type solid)
			)
			(layer "B.Fab")
		)
		(fp_line
			(start -1.269 -1.372)
			(end -1.269 0.915)
			(stroke
				(width 0.15)
				(type solid)
			)
			(layer "B.Fab")
		)
		(fp_text user "${REFERENCE}"
			(at -2.12 -7.399 0)
			(layer "B.Fab")
			(hide yes)
			(effects
				(font
					(size 0.7 0.7)
					(thickness 0.15)
				)
				(justify left bottom mirror)
			)
		)
		(fp_text user "License: Apache-2.0"
			(at -2.12 -6.199 0)
			(layer "B.Fab")
			(hide yes)
			(effects
				(font
					(size 0.7 0.7)
					(thickness 0.15)
				)
				(justify left bottom mirror)
			)
		)
		(fp_text user "Author: Antmicro"
			(at -2.12 -4.999 0)
			(layer "B.Fab")
			(hide yes)
			(effects
				(font
					(size 0.7 0.7)
					(thickness 0.15)
				)
				(justify left bottom mirror)
			)
		)
		(pad "1" smd roundrect
			(at -1.2 0.95 180)
			(size 0.8 0.55)
			(layers "B.Cu" "B.Paste" "B.Mask")
			(roundrect_rratio 0.15)
			(net 561 "/M.2/PCIE_WAKE_SEL0")
			(pintype "input")
		)
		(pad "2" smd roundrect
			(at -1.2 0 180)
			(size 0.8 0.55)
			(layers "B.Cu" "B.Paste" "B.Mask")
			(roundrect_rratio 0.15)
			(net 1 "GND")
			(pinfunction "GND")
			(pintype "power_in")
		)
		(pad "3" smd roundrect
			(at -1.2 -0.95 180)
			(size 0.8 0.55)
			(layers "B.Cu" "B.Paste" "B.Mask")
			(roundrect_rratio 0.15)
			(net 454 "PCIE0_CLKREQ*")
			(pintype "input")
		)
		(pad "4" smd roundrect
			(at 1.2 -0.95 180)
			(size 0.8 0.55)
			(layers "B.Cu" "B.Paste" "B.Mask")
			(roundrect_rratio 0.15)
			(net 248 "/M.2/~{M2_M_CLKREQ0}")
			(pintype "output")
		)
		(pad "5" smd roundrect
			(at 1.2 0 180)
			(size 0.8 0.55)
			(layers "B.Cu" "B.Paste" "B.Mask")
			(roundrect_rratio 0.15)
			(net 635 "/M.2/3V3_M2")
			(pinfunction "V_{CC}")
			(pintype "power_in")
		)
		(pad "6" smd roundrect
			(at 1.2 0.95 180)
			(size 0.8 0.55)
			(layers "B.Cu" "B.Paste" "B.Mask")
			(roundrect_rratio 0.15)
			(net 249 "/M.2/~{M2_M_PEWAKE0}")
			(pintype "output")
		)
	)
	(footprint "antmicro-footprints:TP_SMD_0.75mm"
		(layer "B.Cu")
		(at 69 96.3)
		(property "Reference" "TP20"
			(at 4.98 0.79 180)
			(layer "B.SilkS")
			(hide yes)
			(effects
				(font
					(size 0.7 0.7)
					(thickness 0.15)
				)
				(justify left bottom mirror)
			)
		)
		(property "Value" "TP_0.75mm_SMD"
			(at 0 -1.2 180)
			(layer "B.Fab")
			(effects
				(font
					(size 0.7 0.7)
					(thickness 0.15)
				)
				(justify left bottom mirror)
			)
		)
		(property "Footprint" "antmicro-footprints:TP_SMD_0.75mm"
			(at 0 0 0)
			(layer "F.Fab")
			(hide yes)
			(effects
				(font
					(size 1.27 1.27)
					(thickness 0.15)
				)
			)
		)
		(property "Author" "Antmicro"
			(at 0 0 0)
			(layer "B.Fab")
			(hide yes)
			(effects
				(font
					(size 1 1)
					(thickness 0.15)
				)
				(justify mirror)
			)
		)
		(property "License" "Apache-2.0"
			(at 0 0 0)
			(layer "B.Fab")
			(hide yes)
			(effects
				(font
					(size 1 1)
					(thickness 0.15)
				)
				(justify mirror)
			)
		)
		(property "MPN" ""
			(at 0 0 0)
			(layer "B.Fab")
			(hide yes)
			(effects
				(font
					(size 1 1)
					(thickness 0.15)
				)
				(justify mirror)
			)
		)
		(property "Manufacturer" ""
			(at 0 0 0)
			(layer "B.Fab")
			(hide yes)
			(effects
				(font
					(size 1 1)
					(thickness 0.15)
				)
				(justify mirror)
			)
		)
		(sheetname "USB Debug, DP")
		(sheetfile "usb.kicad_sch")
		(attr exclude_from_pos_files exclude_from_bom)
		(fp_circle
			(center 0 0)
			(end 0.475 0)
			(stroke
				(width 0.05)
				(type default)
			)
			(fill none)
			(layer "B.CrtYd")
		)
		(fp_text user "License: Apache-2.0"
			(at -0.4 -5.101 180)
			(layer "B.Fab")
			(hide yes)
			(effects
				(font
					(size 0.7 0.7)
					(thickness 0.15)
				)
				(justify left bottom mirror)
			)
		)
		(fp_text user "Author: Antmicro"
			(at -0.4 -3.901 180)
			(layer "B.Fab")
			(hide yes)
			(effects
				(font
					(size 0.7 0.7)
					(thickness 0.15)
				)
				(justify left bottom mirror)
			)
		)
		(fp_text user "${REFERENCE}"
			(at -0.4 -2.7 180)
			(layer "B.Fab")
			(hide yes)
			(effects
				(font
					(size 0.7 0.7)
					(thickness 0.15)
				)
				(justify left bottom mirror)
			)
		)
		(pad "1" smd circle
			(at 0 0)
			(size 0.75 0.75)
			(layers "B.Cu" "B.Mask")
			(net 396 "/USB Debug, DP/PDC_I2C2_SDA")
			(pinfunction "1")
			(pintype "passive")
		)
	)
	(footprint "antmicro-footprints:R_0402_1005Metric"
		(layer "B.Cu")
		(at 111.6 92 90)
		(descr "Resistor SMD 0402")
		(tags "resistor SMD 0402")
		(property "Reference" "R13"
			(at 0.83 1.38 -90)
			(layer "B.SilkS")
			(effects
				(font
					(size 0.7 0.7)
					(thickness 0.15)
				)
				(justify left bottom mirror)
			)
		)
		(property "Value" "R_0R_0402"
			(at 0 -1.4 -90)
			(layer "B.Fab")
			(effects
				(font
					(size 0.7 0.7)
					(thickness 0.15)
				)
				(justify left bottom mirror)
			)
		)
		(property "Footprint" "antmicro-footprints:R_0402_1005Metric"
			(at 0 0 90)
			(layer "F.Fab")
			(hide yes)
			(effects
				(font
					(size 1.27 1.27)
					(thickness 0.15)
				)
			)
		)
		(property "Datasheet" "https://industrial.panasonic.com/cdbs/www-data/pdf/RDA0000/AOA0000C301.pdf"
			(at 0 0 90)
			(layer "F.Fab")
			(hide yes)
			(effects
				(font
					(size 1.27 1.27)
					(thickness 0.15)
				)
			)
		)
		(property "Author" "Antmicro"
			(at 203.6 -19.6 0)
			(layer "B.Fab")
			(hide yes)
			(effects
				(font
					(size 1 1)
					(thickness 0.15)
				)
				(justify mirror)
			)
		)
		(property "Current" "1A"
			(at 203.6 -19.6 0)
			(layer "B.Fab")
			(hide yes)
			(effects
				(font
					(size 1 1)
					(thickness 0.15)
				)
				(justify mirror)
			)
		)
		(property "License" "Apache-2.0"
			(at 203.6 -19.6 0)
			(layer "B.Fab")
			(hide yes)
			(effects
				(font
					(size 1 1)
					(thickness 0.15)
				)
				(justify mirror)
			)
		)
		(property "MPN" "ERJ2GE0R00X"
			(at 203.6 -19.6 0)
			(layer "B.Fab")
			(hide yes)
			(effects
				(font
					(size 1 1)
					(thickness 0.15)
				)
				(justify mirror)
			)
		)
		(property "Manufacturer" "Panasonic"
			(at 203.6 -19.6 0)
			(layer "B.Fab")
			(hide yes)
			(effects
				(font
					(size 1 1)
					(thickness 0.15)
				)
				(justify mirror)
			)
		)
		(property "Tolerance" ""
			(at 203.6 -19.6 0)
			(layer "B.Fab")
			(hide yes)
			(effects
				(font
					(size 1 1)
					(thickness 0.15)
				)
				(justify mirror)
			)
		)
		(property "Val" "0R"
			(at 203.6 -19.6 0)
			(layer "B.Fab")
			(hide yes)
			(effects
				(font
					(size 1 1)
					(thickness 0.15)
				)
				(justify mirror)
			)
		)
		(sheetname "M.2")
		(sheetfile "m-2.kicad_sch")
		(attr smd)
		(fp_rect
			(start -0.925 0.47)
			(end 0.925 -0.47)
			(stroke
				(width 0.05)
				(type default)
			)
			(fill none)
			(layer "B.CrtYd")
		)
		(fp_rect
			(start -0.5 0.25)
			(end 0.5 -0.25)
			(stroke
				(width 0.15)
				(type solid)
			)
			(fill none)
			(layer "B.Fab")
		)
		(fp_text user "${REFERENCE}"
			(at -0.95 -3.168 -90)
			(layer "B.Fab")
			(hide yes)
			(effects
				(font
					(size 0.7 0.7)
					(thickness 0.15)
				)
				(justify left bottom mirror)
			)
		)
		(fp_text user "Author: Antmicro"
			(at -0.95 -4.169 -90)
			(layer "B.Fab")
			(hide yes)
			(effects
				(font
					(size 0.7 0.7)
					(thickness 0.15)
				)
				(justify left bottom mirror)
			)
		)
		(fp_text user "License: Apache-2.0"
			(at -0.95 -5.169 -90)
			(layer "B.Fab")
			(hide yes)
			(effects
				(font
					(size 0.7 0.7)
					(thickness 0.15)
				)
				(justify left bottom mirror)
			)
		)
		(pad "1" smd roundrect
			(at -0.48 0 90)
			(size 0.59 0.64)
			(layers "B.Cu" "B.Paste" "B.Mask")
			(roundrect_rratio 0.25)
			(net 453 "PCIE_WAKE*")
			(pintype "passive")
		)
		(pad "2" smd roundrect
			(at 0.48 0 90)
			(size 0.59 0.64)
			(layers "B.Cu" "B.Paste" "B.Mask")
			(roundrect_rratio 0.25)
			(net 561 "/M.2/PCIE_WAKE_SEL0")
			(pintype "passive")
		)
	)
	(footprint "antmicro-footprints:R_0402_1005Metric"
		(layer "B.Cu")
		(at 112.5 80.4)
		(descr "Resistor SMD 0402")
		(tags "resistor SMD 0402")
		(property "Reference" "R19"
			(at 1 -0.4 180)
			(layer "B.SilkS")
			(effects
				(font
					(size 0.7 0.7)
					(thickness 0.15)
				)
				(justify left bottom mirror)
			)
		)
		(property "Value" "R_0R_0402"
			(at 0 -1.4 180)
			(layer "B.Fab")
			(effects
				(font
					(size 0.7 0.7)
					(thickness 0.15)
				)
				(justify left bottom mirror)
			)
		)
		(property "Footprint" "antmicro-footprints:R_0402_1005Metric"
			(at 0 0 0)
			(layer "F.Fab")
			(hide yes)
			(effects
				(font
					(size 1.27 1.27)
					(thickness 0.15)
				)
			)
		)
		(property "Datasheet" "https://industrial.panasonic.com/cdbs/www-data/pdf/RDA0000/AOA0000C301.pdf"
			(at 0 0 0)
			(layer "F.Fab")
			(hide yes)
			(effects
				(font
					(size 1.27 1.27)
					(thickness 0.15)
				)
			)
		)
		(property "Author" "Antmicro"
			(at 0 0 0)
			(layer "B.Fab")
			(hide yes)
			(effects
				(font
					(size 1 1)
					(thickness 0.15)
				)
				(justify mirror)
			)
		)
		(property "Current" "1A"
			(at 0 0 0)
			(layer "B.Fab")
			(hide yes)
			(effects
				(font
					(size 1 1)
					(thickness 0.15)
				)
				(justify mirror)
			)
		)
		(property "License" "Apache-2.0"
			(at 0 0 0)
			(layer "B.Fab")
			(hide yes)
			(effects
				(font
					(size 1 1)
					(thickness 0.15)
				)
				(justify mirror)
			)
		)
		(property "MPN" "ERJ2GE0R00X"
			(at 0 0 0)
			(layer "B.Fab")
			(hide yes)
			(effects
				(font
					(size 1 1)
					(thickness 0.15)
				)
				(justify mirror)
			)
		)
		(property "Manufacturer" "Panasonic"
			(at 0 0 0)
			(layer "B.Fab")
			(hide yes)
			(effects
				(font
					(size 1 1)
					(thickness 0.15)
				)
				(justify mirror)
			)
		)
		(property "Tolerance" ""
			(at 0 0 0)
			(layer "B.Fab")
			(hide yes)
			(effects
				(font
					(size 1 1)
					(thickness 0.15)
				)
				(justify mirror)
			)
		)
		(property "Val" "0R"
			(at 0 0 0)
			(layer "B.Fab")
			(hide yes)
			(effects
				(font
					(size 1 1)
					(thickness 0.15)
				)
				(justify mirror)
			)
		)
		(sheetname "M.2")
		(sheetfile "m-2.kicad_sch")
		(attr smd)
		(fp_rect
			(start -0.925 0.47)
			(end 0.925 -0.47)
			(stroke
				(width 0.05)
				(type default)
			)
			(fill none)
			(layer "B.CrtYd")
		)
		(fp_rect
			(start -0.5 0.25)
			(end 0.5 -0.25)
			(stroke
				(width 0.15)
				(type solid)
			)
			(fill none)
			(layer "B.Fab")
		)
		(fp_text user "Author: Antmicro"
			(at -0.95 -4.169 180)
			(layer "B.Fab")
			(hide yes)
			(effects
				(font
					(size 0.7 0.7)
					(thickness 0.15)
				)
				(justify left bottom mirror)
			)
		)
		(fp_text user "License: Apache-2.0"
			(at -0.95 -5.169 180)
			(layer "B.Fab")
			(hide yes)
			(effects
				(font
					(size 0.7 0.7)
					(thickness 0.15)
				)
				(justify left bottom mirror)
			)
		)
		(fp_text user "${REFERENCE}"
			(at -0.95 -3.168 180)
			(layer "B.Fab")
			(hide yes)
			(effects
				(font
					(size 0.7 0.7)
					(thickness 0.15)
				)
				(justify left bottom mirror)
			)
		)
		(pad "1" smd roundrect
			(at -0.48 0)
			(size 0.59 0.64)
			(layers "B.Cu" "B.Paste" "B.Mask")
			(roundrect_rratio 0.25)
			(net 456 "/M.2/32.7KHZ_OUT")
			(pintype "passive")
		)
		(pad "2" smd roundrect
			(at 0.48 0)
			(size 0.59 0.64)
			(layers "B.Cu" "B.Paste" "B.Mask")
			(roundrect_rratio 0.25)
			(net 250 "/M.2/M2_M_SUSCLK")
			(pintype "passive")
		)
	)
	(footprint "antmicro-footprints:SOD-923"
		(layer "B.Cu")
		(at 53.4 76.8 90)
		(property "Reference" "D29"
			(at -7.4 21.75 90)
			(unlocked yes)
			(layer "B.SilkS")
			(effects
				(font
					(size 0.7 0.7)
					(thickness 0.15)
				)
				(justify left bottom mirror)
			)
		)
		(property "Value" "DF2S30FS_SOD"
			(at 0 -1.3 -90)
			(unlocked yes)
			(layer "B.Fab")
			(effects
				(font
					(size 0.7 0.7)
					(thickness 0.15)
				)
				(justify left bottom mirror)
			)
		)
		(property "Footprint" "antmicro-footprints:SOD-923"
			(at 0 0 90)
			(layer "F.Fab")
			(hide yes)
			(effects
				(font
					(size 1.27 1.27)
					(thickness 0.15)
				)
			)
		)
		(property "Datasheet" "https://toshiba.semicon-storage.com/info/DF2S30FS_datasheet_en_20211216.pdf?did=11156&prodName=DF2S30FS"
			(at 0 0 90)
			(layer "F.Fab")
			(hide yes)
			(effects
				(font
					(size 1.27 1.27)
					(thickness 0.15)
				)
			)
		)
		(property "Author" "Antmicro"
			(at 130.2 23.4 0)
			(layer "B.Fab")
			(hide yes)
			(effects
				(font
					(size 1 1)
					(thickness 0.15)
				)
				(justify mirror)
			)
		)
		(property "License" "Apache-2.0"
			(at 130.2 23.4 0)
			(layer "B.Fab")
			(hide yes)
			(effects
				(font
					(size 1 1)
					(thickness 0.15)
				)
				(justify mirror)
			)
		)
		(property "MPN" "DF2S30FS"
			(at 130.2 23.4 0)
			(layer "B.Fab")
			(hide yes)
			(effects
				(font
					(size 1 1)
					(thickness 0.15)
				)
				(justify mirror)
			)
		)
		(property "Manufacturer" "Toshiba"
			(at 130.2 23.4 0)
			(layer "B.Fab")
			(hide yes)
			(effects
				(font
					(size 1 1)
					(thickness 0.15)
				)
				(justify mirror)
			)
		)
		(sheetname "Supply")
		(sheetfile "supply.kicad_sch")
		(attr smd)
		(fp_line
			(start 0.5 -0.4)
			(end -0.5 -0.4)
			(stroke
				(width 0.15)
				(type solid)
			)
			(layer "B.SilkS")
		)
		(fp_line
			(start -0.16 -0.4)
			(end -0.16 0.4)
			(stroke
				(width 0.15)
				(type solid)
			)
			(layer "B.SilkS")
		)
		(fp_line
			(start 0.5 -0.3)
			(end 0.5 -0.4)
			(stroke
				(width 0.15)
				(type solid)
			)
			(layer "B.SilkS")
		)
		(fp_line
			(start -0.5 -0.3)
			(end -0.5 -0.4)
			(stroke
				(width 0.15)
				(type solid)
			)
			(layer "B.SilkS")
		)
		(fp_line
			(start 0.5 0.3)
			(end 0.5 0.4)
			(stroke
				(width 0.15)
				(type solid)
			)
			(layer "B.SilkS")
		)
		(fp_line
			(start 0.5 0.4)
			(end -0.5 0.4)
			(stroke
				(width 0.15)
				(type solid)
			)
			(layer "B.SilkS")
		)
		(fp_line
			(start -0.5 0.4)
			(end -0.5 0.3)
			(stroke
				(width 0.15)
				(type solid)
			)
			(layer "B.SilkS")
		)
		(fp_rect
			(start -0.68 0.41)
			(end 0.68 -0.41)
			(stroke
				(width 0.05)
				(type solid)
			)
			(fill none)
			(layer "B.CrtYd")
		)
		(fp_line
			(start -0.202 -0.298)
			(end -0.202 0.3)
			(stroke
				(width 0.15)
				(type solid)
			)
			(layer "B.Fab")
		)
		(fp_rect
			(start -0.402 0.3)
			(end 0.4 -0.298)
			(stroke
				(width 0.15)
				(type solid)
			)
			(fill none)
			(layer "B.Fab")
		)
		(fp_text user "Author: Antmicro"
			(at -0.68 -5.7 -90)
			(layer "B.Fab")
			(hide yes)
			(effects
				(font
					(size 0.7 0.7)
					(thickness 0.15)
				)
				(justify left bottom mirror)
			)
		)
		(fp_text user "License: Apache-2.0"
			(at -0.68 -4.5 -90)
			(layer "B.Fab")
			(hide yes)
			(effects
				(font
					(size 0.7 0.7)
					(thickness 0.15)
				)
				(justify left bottom mirror)
			)
		)
		(fp_text user "${REFERENCE}"
			(at -0.68 -3.3 -90)
			(unlocked yes)
			(layer "B.Fab")
			(hide yes)
			(effects
				(font
					(size 0.7 0.7)
					(thickness 0.15)
				)
				(justify left bottom mirror)
			)
		)
		(pad "1" smd roundrect
			(at -0.438 0 90)
			(size 0.4 0.325)
			(layers "B.Cu" "B.Paste" "B.Mask")
			(roundrect_rratio 0.25)
			(net 115 "VCC")
			(pinfunction "C")
			(pintype "passive")
		)
		(pad "2" smd roundrect
			(at 0.436 0 90)
			(size 0.4 0.325)
			(layers "B.Cu" "B.Paste" "B.Mask")
			(roundrect_rratio 0.25)
			(net 1 "GND")
			(pinfunction "A")
			(pintype "passive")
		)
	)
)
